(kicad_pcb
	(version 20260206)
	(generator "pcbnew")
	(generator_version "10.0")
	(general
		(thickness 1.6)
		(legacy_teardrops no)
	)
	(paper "A4")
	(title_block
		(title "v1-chassis-manager — T6M_CM_d_v01_1031_1645.brd")
		(comment 1 "Open CloudServer (Microsoft) / footprints 2492-2500 of 2512")
	)
	(layers
		(0 "F.Cu" signal "TOP")
		(4 "In1.Cu" signal "GND1")
		(6 "In2.Cu" signal "IN1")
		(8 "In3.Cu" signal "VCC1")
		(10 "In4.Cu" signal "VCC2")
		(12 "In5.Cu" signal "GND2")
		(14 "In6.Cu" signal "IN2")
		(16 "In7.Cu" signal "IN3")
		(18 "In8.Cu" signal "GND3")
		(2 "B.Cu" signal "BOTTOM")
		(9 "F.Adhes" user "F.Adhesive")
		(11 "B.Adhes" user "B.Adhesive")
		(13 "F.Paste" user "Package Geometry/Pastemask Top")
		(15 "B.Paste" user "Package Geometry/Pastemask Bottom")
		(5 "F.SilkS" user "Ref Des/Silkscreen Top")
		(7 "B.SilkS" user "Ref Des/Silkscreen Bottom")
		(1 "F.Mask" user "Board Geometry/Soldermask Top")
		(3 "B.Mask" user "Board Geometry/Soldermask Bottom")
		(17 "Dwgs.User" user "User.Drawings")
		(19 "Cmts.User" user "User.Comments")
		(21 "Eco1.User" user "User.Eco1")
		(23 "Eco2.User" user "User.Eco2")
		(25 "Edge.Cuts" user "Board Geometry/Outline")
		(27 "Margin" user)
		(31 "F.CrtYd" user "Package Geometry/Place Bound Top")
		(29 "B.CrtYd" user "Package Geometry/Place Bound Bottom")
		(35 "F.Fab" user "Ref Des/Assembly Top")
		(33 "B.Fab" user "Ref Des/Assembly Bottom")
	)
	(footprint ""
		(layer "B.Cu")
		(at 162.089592 -107.398566)
		(property "Reference" "L34"
			(at 1.326642 1.183386 270)
			(unlocked yes)
			(layer "B.SilkS")
			(effects
				(font
					(size 0.7874 0.5842)
					(thickness 0.1524)
				)
				(justify left mirror)
			)
		)
		(property "Value" ""
			(at 0 0 0)
			(layer "B.Fab")
			(effects
				(font
					(size 1.27 1.27)
				)
				(justify mirror)
			)
		)
		(duplicate_pad_numbers_are_jumpers no)
		(fp_line
			(start -0.700024 -1.459992)
			(end -0.700024 1.439926)
			(stroke
				(width 0.1524)
				(type default)
			)
			(layer "B.SilkS")
		)
		(fp_line
			(start -0.700024 0.195326)
			(end 0.700024 0.195326)
			(stroke
				(width 0.1524)
				(type default)
			)
			(layer "B.SilkS")
		)
		(fp_line
			(start -0.700024 1.439926)
			(end 0.700024 1.439926)
			(stroke
				(width 0.1524)
				(type default)
			)
			(layer "B.SilkS")
		)
		(fp_line
			(start 0.700024 -1.459992)
			(end -0.700024 -1.459992)
			(stroke
				(width 0.1524)
				(type default)
			)
			(layer "B.SilkS")
		)
		(fp_line
			(start 0.700024 -0.139192)
			(end -0.700024 -0.139192)
			(stroke
				(width 0.1524)
				(type default)
			)
			(layer "B.SilkS")
		)
		(fp_line
			(start 0.700024 1.439926)
			(end 0.700024 -1.459992)
			(stroke
				(width 0.1524)
				(type default)
			)
			(layer "B.SilkS")
		)
		(fp_poly
			(pts
				(xy 0.700024 1.100074) (xy 0.5842 1.100074) (xy 0.5842 1.3716) (xy -0.5842 1.3716) (xy -0.5842 1.100074)
				(xy -0.700024 1.100074) (xy -0.700024 -1.100074) (xy -0.5842 -1.100074) (xy -0.5842 -1.3716) (xy 0.5842 -1.3716)
				(xy 0.5842 -1.100074) (xy 0.700024 -1.100074)
			)
			(stroke
				(width 0)
				(type default)
			)
			(fill no)
			(layer "B.CrtYd")
		)
		(fp_line
			(start -0.700024 -1.100074)
			(end -0.700024 1.100074)
			(stroke
				(width 0.1)
				(type default)
			)
			(layer "B.Fab")
		)
		(fp_line
			(start -0.700024 1.100074)
			(end 0.700024 1.100074)
			(stroke
				(width 0.1)
				(type default)
			)
			(layer "B.Fab")
		)
		(fp_line
			(start 0.700024 -1.100074)
			(end -0.700024 -1.100074)
			(stroke
				(width 0.1)
				(type default)
			)
			(layer "B.Fab")
		)
		(fp_line
			(start 0.700024 1.100074)
			(end 0.700024 -1.100074)
			(stroke
				(width 0.1)
				(type default)
			)
			(layer "B.Fab")
		)
		(pad "1" smd rect
			(at 0 -0.899922 270)
			(size 0.8128 1.016)
			(layers "B.Cu" "B.Mask" "B.Paste")
			(net "P3V3_NODE1")
		)
		(pad "2" smd rect
			(at 0 0.899922 270)
			(size 0.8128 1.016)
			(layers "B.Cu" "B.Mask" "B.Paste")
			(net "P3V3_USB_NODE1")
		)
	)
	(footprint ""
		(layer "B.Cu")
		(at 48.75022 -159.29229 180)
		(property "Reference" "C394"
			(at 11.81354 3.457194 0)
			(unlocked yes)
			(layer "B.SilkS")
			(effects
				(font
					(size 0.7874 0.5842)
					(thickness 0.1524)
				)
				(justify left mirror)
			)
		)
		(property "Value" ""
			(at 0 0 0)
			(layer "B.Fab")
			(effects
				(font
					(size 1.27 1.27)
				)
				(justify mirror)
			)
		)
		(duplicate_pad_numbers_are_jumpers no)
		(fp_line
			(start 0.7874 0.4064)
			(end 0.7874 -0.4064)
			(stroke
				(width 0.1524)
				(type default)
			)
			(layer "B.SilkS")
		)
		(fp_line
			(start 0.7874 -0.4064)
			(end -0.7874 -0.4064)
			(stroke
				(width 0.1524)
				(type default)
			)
			(layer "B.SilkS")
		)
		(fp_line
			(start 0 0.381)
			(end 0 -0.381)
			(stroke
				(width 0.1524)
				(type default)
			)
			(layer "B.SilkS")
		)
		(fp_line
			(start -0.7874 0.4064)
			(end 0.7874 0.4064)
			(stroke
				(width 0.1524)
				(type default)
			)
			(layer "B.SilkS")
		)
		(fp_line
			(start -0.7874 -0.4064)
			(end -0.7874 0.4064)
			(stroke
				(width 0.1524)
				(type default)
			)
			(layer "B.SilkS")
		)
		(fp_poly
			(pts
				(xy 0.5334 0.254) (xy 0.635 0.254) (xy 0.635 0.2286) (xy 0.635 -0.254) (xy 0.5334 -0.254) (xy 0.5334 -0.2794)
				(xy -0.5334 -0.2794) (xy -0.5334 -0.254) (xy -0.635 -0.254) (xy -0.635 0.254) (xy -0.5334 0.254)
				(xy -0.5334 0.2794) (xy 0.508 0.2794) (xy 0.5334 0.2794)
			)
			(stroke
				(width 0)
				(type default)
			)
			(fill no)
			(layer "B.CrtYd")
		)
		(pad "1" smd rect
			(at -0.40005 0)
			(size 0.4572 0.508)
			(layers "B.Cu" "B.Mask" "B.Paste")
			(net "P3V3_NODE1")
		)
		(pad "2" smd rect
			(at 0.40005 0)
			(size 0.4572 0.508)
			(layers "B.Cu" "B.Mask" "B.Paste")
			(net "GND")
		)
	)
	(footprint ""
		(layer "B.Cu")
		(at 60.615322 -92.042234 90)
		(property "Reference" "R59"
			(at -1.062228 2.519426 270)
			(unlocked yes)
			(layer "B.SilkS")
			(effects
				(font
					(size 0.7874 0.5842)
					(thickness 0.1524)
				)
				(justify left mirror)
			)
		)
		(property "Value" ""
			(at 0 0 90)
			(layer "B.Fab")
			(effects
				(font
					(size 1.27 1.27)
				)
				(justify mirror)
			)
		)
		(duplicate_pad_numbers_are_jumpers no)
		(fp_line
			(start 0.7874 -0.4064)
			(end -0.7874 -0.4064)
			(stroke
				(width 0.1524)
				(type default)
			)
			(layer "B.SilkS")
		)
		(fp_line
			(start -0.7874 -0.4064)
			(end -0.7874 0.4064)
			(stroke
				(width 0.1524)
				(type default)
			)
			(layer "B.SilkS")
		)
		(fp_line
			(start 0.7874 0.4064)
			(end 0.7874 -0.4064)
			(stroke
				(width 0.1524)
				(type default)
			)
			(layer "B.SilkS")
		)
		(fp_line
			(start -0.7874 0.4064)
			(end 0.7874 0.4064)
			(stroke
				(width 0.1524)
				(type default)
			)
			(layer "B.SilkS")
		)
		(fp_poly
			(pts
				(xy 0.508 0.2794) (xy 0.508 0.2286) (xy 0.635 0.2286) (xy 0.635 -0.254) (xy 0.5334 -0.254) (xy 0.5334 -0.2794)
				(xy -0.5334 -0.2794) (xy -0.5334 -0.254) (xy -0.635 -0.254) (xy -0.635 0.254) (xy -0.5334 0.254)
				(xy -0.5334 0.2794)
			)
			(stroke
				(width 0)
				(type default)
			)
			(fill no)
			(layer "B.CrtYd")
		)
		(pad "1" smd rect
			(at -0.40005 0 270)
			(size 0.4572 0.508)
			(layers "B.Cu" "B.Mask" "B.Paste")
			(net "SPI_CPU_NODE1_SCLK_R")
		)
		(pad "2" smd rect
			(at 0.40005 0 270)
			(size 0.4572 0.508)
			(layers "B.Cu" "B.Mask" "B.Paste")
			(net "SPI_CPU_NODE1_SCLK")
		)
	)
	(footprint ""
		(layer "B.Cu")
		(at 116.44376 -188.126624 90)
		(property "Reference" "R955"
			(at 4.080256 0.69088 270)
			(unlocked yes)
			(layer "B.SilkS")
			(effects
				(font
					(size 0.7874 0.5842)
					(thickness 0.1524)
				)
				(justify left mirror)
			)
		)
		(property "Value" ""
			(at 0 0 90)
			(layer "B.Fab")
			(effects
				(font
					(size 1.27 1.27)
				)
				(justify mirror)
			)
		)
		(duplicate_pad_numbers_are_jumpers no)
		(fp_line
			(start 0.7874 -0.4064)
			(end -0.7874 -0.4064)
			(stroke
				(width 0.1524)
				(type default)
			)
			(layer "B.SilkS")
		)
		(fp_line
			(start -0.7874 -0.4064)
			(end -0.7874 0.4064)
			(stroke
				(width 0.1524)
				(type default)
			)
			(layer "B.SilkS")
		)
		(fp_line
			(start 0.7874 0.4064)
			(end 0.7874 -0.4064)
			(stroke
				(width 0.1524)
				(type default)
			)
			(layer "B.SilkS")
		)
		(fp_line
			(start -0.7874 0.4064)
			(end 0.7874 0.4064)
			(stroke
				(width 0.1524)
				(type default)
			)
			(layer "B.SilkS")
		)
		(fp_poly
			(pts
				(xy 0.508 0.2794) (xy 0.508 0.2286) (xy 0.635 0.2286) (xy 0.635 -0.254) (xy 0.5334 -0.254) (xy 0.5334 -0.2794)
				(xy -0.5334 -0.2794) (xy -0.5334 -0.254) (xy -0.635 -0.254) (xy -0.635 0.254) (xy -0.5334 0.254)
				(xy -0.5334 0.2794)
			)
			(stroke
				(width 0)
				(type default)
			)
			(fill no)
			(layer "B.CrtYd")
		)
		(pad "1" smd rect
			(at -0.40005 0 270)
			(size 0.4572 0.508)
			(layers "B.Cu" "B.Mask" "B.Paste")
			(net "UART_T7_NODE1_RXD")
		)
		(pad "2" smd rect
			(at 0.40005 0 270)
			(size 0.4572 0.508)
			(layers "B.Cu" "B.Mask" "B.Paste")
			(net "UART_T7_NODE1_RXD_R")
		)
	)
	(footprint ""
		(layer "B.Cu")
		(at 83.021678 -29.82214)
		(property "Reference" "C174"
			(at -0.046482 1.340866 0)
			(unlocked yes)
			(layer "B.SilkS")
			(effects
				(font
					(size 0.7874 0.5842)
					(thickness 0.1524)
				)
				(justify mirror)
			)
		)
		(property "Value" ""
			(at 0 0 0)
			(layer "B.Fab")
			(effects
				(font
					(size 1.27 1.27)
				)
				(justify mirror)
			)
		)
		(duplicate_pad_numbers_are_jumpers no)
		(fp_line
			(start -1.2954 -0.5842)
			(end -1.2954 0.5842)
			(stroke
				(width 0.1524)
				(type default)
			)
			(layer "B.SilkS")
		)
		(fp_line
			(start -1.2954 0.5842)
			(end 1.2954 0.5842)
			(stroke
				(width 0.1524)
				(type default)
			)
			(layer "B.SilkS")
		)
		(fp_line
			(start 0 -0.5842)
			(end 0 0.5842)
			(stroke
				(width 0.1524)
				(type default)
			)
			(layer "B.SilkS")
		)
		(fp_line
			(start 1.2954 -0.5842)
			(end -1.2954 -0.5842)
			(stroke
				(width 0.1524)
				(type default)
			)
			(layer "B.SilkS")
		)
		(fp_line
			(start 1.2954 0.5842)
			(end 1.2954 -0.5842)
			(stroke
				(width 0.1524)
				(type default)
			)
			(layer "B.SilkS")
		)
		(fp_poly
			(pts
				(xy -0.8636 -0.4572) (xy -0.8636 -0.3556) (xy -1.143 -0.3556) (xy -1.143 0.3556) (xy -0.8636 0.3556)
				(xy -0.8636 0.4572) (xy 0.8636 0.4572) (xy 0.8636 0.3556) (xy 1.143 0.3556) (xy 1.143 -0.3556) (xy 0.8636 -0.3556)
				(xy 0.8636 -0.4572)
			)
			(stroke
				(width 0)
				(type default)
			)
			(fill no)
			(layer "B.CrtYd")
		)
		(fp_line
			(start -0.884936 -0.504952)
			(end -0.884936 0.504952)
			(stroke
				(width 0.1)
				(type default)
			)
			(layer "B.Fab")
		)
		(fp_line
			(start -0.884936 0.504952)
			(end 0.884936 0.504952)
			(stroke
				(width 0.1)
				(type default)
			)
			(layer "B.Fab")
		)
		(fp_line
			(start 0.884936 -0.504952)
			(end -0.884936 -0.504952)
			(stroke
				(width 0.1)
				(type default)
			)
			(layer "B.Fab")
		)
		(fp_line
			(start 0.884936 0.504952)
			(end 0.884936 -0.504952)
			(stroke
				(width 0.1)
				(type default)
			)
			(layer "B.Fab")
		)
		(pad "1" smd rect
			(at -0.7366 0 90)
			(size 0.7112 0.8128)
			(layers "B.Cu" "B.Mask" "B.Paste")
			(net "PV_VDDR_NODE1")
		)
		(pad "2" smd rect
			(at 0.7366 0 90)
			(size 0.7112 0.8128)
			(layers "B.Cu" "B.Mask" "B.Paste")
			(net "GND")
		)
	)
	(footprint ""
		(layer "B.Cu")
		(at 37.25545 -104.654096 90)
		(property "Reference" "C822"
			(at 1.103376 1.638046 270)
			(unlocked yes)
			(layer "B.SilkS")
			(effects
				(font
					(size 0.7874 0.5842)
					(thickness 0.1524)
				)
				(justify left mirror)
			)
		)
		(property "Value" ""
			(at 0 0 90)
			(layer "B.Fab")
			(effects
				(font
					(size 1.27 1.27)
				)
				(justify mirror)
			)
		)
		(duplicate_pad_numbers_are_jumpers no)
		(fp_line
			(start 0.7874 -0.4064)
			(end -0.7874 -0.4064)
			(stroke
				(width 0.1524)
				(type default)
			)
			(layer "B.SilkS")
		)
		(fp_line
			(start -0.7874 -0.4064)
			(end -0.7874 0.4064)
			(stroke
				(width 0.1524)
				(type default)
			)
			(layer "B.SilkS")
		)
		(fp_line
			(start 0 0.381)
			(end 0 -0.381)
			(stroke
				(width 0.1524)
				(type default)
			)
			(layer "B.SilkS")
		)
		(fp_line
			(start 0.7874 0.4064)
			(end 0.7874 -0.4064)
			(stroke
				(width 0.1524)
				(type default)
			)
			(layer "B.SilkS")
		)
		(fp_line
			(start -0.7874 0.4064)
			(end 0.7874 0.4064)
			(stroke
				(width 0.1524)
				(type default)
			)
			(layer "B.SilkS")
		)
		(fp_poly
			(pts
				(xy 0.5334 0.254) (xy 0.635 0.254) (xy 0.635 0.2286) (xy 0.635 -0.254) (xy 0.5334 -0.254) (xy 0.5334 -0.2794)
				(xy -0.5334 -0.2794) (xy -0.5334 -0.254) (xy -0.635 -0.254) (xy -0.635 0.254) (xy -0.5334 0.254)
				(xy -0.5334 0.2794) (xy 0.508 0.2794) (xy 0.5334 0.2794)
			)
			(stroke
				(width 0)
				(type default)
			)
			(fill no)
			(layer "B.CrtYd")
		)
		(pad "1" smd rect
			(at -0.40005 0 270)
			(size 0.4572 0.508)
			(layers "B.Cu" "B.Mask" "B.Paste")
			(net "P1V5_SUS_NODE1")
		)
		(pad "2" smd rect
			(at 0.40005 0 270)
			(size 0.4572 0.508)
			(layers "B.Cu" "B.Mask" "B.Paste")
			(net "GND")
		)
	)
	(footprint ""
		(layer "B.Cu")
		(at 50.53076 -181.992524 -90)
		(property "Reference" "C606"
			(at 3.618738 10.515346 270)
			(unlocked yes)
			(layer "B.SilkS")
			(effects
				(font
					(size 0.7874 0.5842)
					(thickness 0.1524)
				)
				(justify left mirror)
			)
		)
		(property "Value" ""
			(at 0 0 90)
			(layer "B.Fab")
			(effects
				(font
					(size 1.27 1.27)
				)
				(justify mirror)
			)
		)
		(duplicate_pad_numbers_are_jumpers no)
		(fp_line
			(start -0.7874 0.4064)
			(end 0.7874 0.4064)
			(stroke
				(width 0.1524)
				(type default)
			)
			(layer "B.SilkS")
		)
		(fp_line
			(start 0.7874 0.4064)
			(end 0.7874 -0.4064)
			(stroke
				(width 0.1524)
				(type default)
			)
			(layer "B.SilkS")
		)
		(fp_line
			(start 0 0.381)
			(end 0 -0.381)
			(stroke
				(width 0.1524)
				(type default)
			)
			(layer "B.SilkS")
		)
		(fp_line
			(start -0.7874 -0.4064)
			(end -0.7874 0.4064)
			(stroke
				(width 0.1524)
				(type default)
			)
			(layer "B.SilkS")
		)
		(fp_line
			(start 0.7874 -0.4064)
			(end -0.7874 -0.4064)
			(stroke
				(width 0.1524)
				(type default)
			)
			(layer "B.SilkS")
		)
		(fp_poly
			(pts
				(xy 0.5334 0.254) (xy 0.635 0.254) (xy 0.635 0.2286) (xy 0.635 -0.254) (xy 0.5334 -0.254) (xy 0.5334 -0.2794)
				(xy -0.5334 -0.2794) (xy -0.5334 -0.254) (xy -0.635 -0.254) (xy -0.635 0.254) (xy -0.5334 0.254)
				(xy -0.5334 0.2794) (xy 0.508 0.2794) (xy 0.5334 0.2794)
			)
			(stroke
				(width 0)
				(type default)
			)
			(fill no)
			(layer "B.CrtYd")
		)
		(pad "1" smd rect
			(at -0.40005 0 90)
			(size 0.4572 0.508)
			(layers "B.Cu" "B.Mask" "B.Paste")
			(net "PSU3_DC_OK_R_BUF")
		)
		(pad "2" smd rect
			(at 0.40005 0 90)
			(size 0.4572 0.508)
			(layers "B.Cu" "B.Mask" "B.Paste")
			(net "GND")
		)
	)
	(footprint ""
		(layer "B.Cu")
		(at 116.570252 -166.020242 90)
		(property "Reference" "R1245"
			(at -3.951986 1.640078 270)
			(unlocked yes)
			(layer "B.SilkS")
			(effects
				(font
					(size 0.7874 0.5842)
					(thickness 0.1524)
				)
				(justify left mirror)
			)
		)
		(property "Value" ""
			(at 0 0 90)
			(layer "B.Fab")
			(effects
				(font
					(size 1.27 1.27)
				)
				(justify mirror)
			)
		)
		(duplicate_pad_numbers_are_jumpers no)
		(fp_line
			(start 0.7874 -0.4064)
			(end -0.7874 -0.4064)
			(stroke
				(width 0.1524)
				(type default)
			)
			(layer "B.SilkS")
		)
		(fp_line
			(start -0.7874 -0.4064)
			(end -0.7874 0.4064)
			(stroke
				(width 0.1524)
				(type default)
			)
			(layer "B.SilkS")
		)
		(fp_line
			(start 0.7874 0.4064)
			(end 0.7874 -0.4064)
			(stroke
				(width 0.1524)
				(type default)
			)
			(layer "B.SilkS")
		)
		(fp_line
			(start -0.7874 0.4064)
			(end 0.7874 0.4064)
			(stroke
				(width 0.1524)
				(type default)
			)
			(layer "B.SilkS")
		)
		(fp_poly
			(pts
				(xy 0.508 0.2794) (xy 0.508 0.2286) (xy 0.635 0.2286) (xy 0.635 -0.254) (xy 0.5334 -0.254) (xy 0.5334 -0.2794)
				(xy -0.5334 -0.2794) (xy -0.5334 -0.254) (xy -0.635 -0.254) (xy -0.635 0.254) (xy -0.5334 0.254)
				(xy -0.5334 0.2794)
			)
			(stroke
				(width 0)
				(type default)
			)
			(fill no)
			(layer "B.CrtYd")
		)
		(pad "1" smd rect
			(at -0.40005 0 270)
			(size 0.4572 0.508)
			(layers "B.Cu" "B.Mask" "B.Paste")
			(net "GND")
		)
		(pad "2" smd rect
			(at 0.40005 0 270)
			(size 0.4572 0.508)
			(layers "B.Cu" "B.Mask" "B.Paste")
			(net "PSU3_HUB_EN")
		)
	)
	(footprint ""
		(layer "B.Cu")
		(at 66.425572 -77.974698)
		(property "Reference" "R101"
			(at -13.110972 31.287974 0)
			(unlocked yes)
			(layer "B.SilkS")
			(effects
				(font
					(size 0.7874 0.5842)
					(thickness 0.1524)
				)
				(justify left mirror)
			)
		)
		(property "Value" ""
			(at 0 0 0)
			(layer "B.Fab")
			(effects
				(font
					(size 1.27 1.27)
				)
				(justify mirror)
			)
		)
		(duplicate_pad_numbers_are_jumpers no)
		(fp_line
			(start -0.7874 -0.4064)
			(end -0.7874 0.4064)
			(stroke
				(width 0.1524)
				(type default)
			)
			(layer "B.SilkS")
		)
		(fp_line
			(start -0.7874 0.4064)
			(end 0.7874 0.4064)
			(stroke
				(width 0.1524)
				(type default)
			)
			(layer "B.SilkS")
		)
		(fp_line
			(start 0.7874 -0.4064)
			(end -0.7874 -0.4064)
			(stroke
				(width 0.1524)
				(type default)
			)
			(layer "B.SilkS")
		)
		(fp_line
			(start 0.7874 0.4064)
			(end 0.7874 -0.4064)
			(stroke
				(width 0.1524)
				(type default)
			)
			(layer "B.SilkS")
		)
		(fp_poly
			(pts
				(xy 0.508 0.2794) (xy 0.508 0.2286) (xy 0.635 0.2286) (xy 0.635 -0.254) (xy 0.5334 -0.254) (xy 0.5334 -0.2794)
				(xy -0.5334 -0.2794) (xy -0.5334 -0.254) (xy -0.635 -0.254) (xy -0.635 0.254) (xy -0.5334 0.254)
				(xy -0.5334 0.2794)
			)
			(stroke
				(width 0)
				(type default)
			)
			(fill no)
			(layer "B.CrtYd")
		)
		(pad "1" smd rect
			(at -0.40005 0 180)
			(size 0.4572 0.508)
			(layers "B.Cu" "B.Mask" "B.Paste")
			(net "A_CPU_NODE1_LV_GPIO_RCOMP")
		)
		(pad "2" smd rect
			(at 0.40005 0 180)
			(size 0.4572 0.508)
			(layers "B.Cu" "B.Mask" "B.Paste")
			(net "GND")
		)
	)
)
